(kicad_pcb
	(version 20260206)
	(generator "pcbnew")
	(generator_version "10.0")
	(general
		(thickness 1.6)
		(legacy_teardrops no)
	)
	(paper "A4")
	(title_block
		(title "9052_F0T_PDB_Converter_Brick_F_V03_1208_1600_OCP.brd")
		(comment 1 "Grand Teton / footprints 8-16 of 578")
	)
	(layers
		(0 "F.Cu" signal "TOP")
		(4 "In1.Cu" signal "GND")
		(6 "In2.Cu" signal "IN1")
		(8 "In3.Cu" signal "GND1")
		(10 "In4.Cu" signal "VCC")
		(12 "In5.Cu" signal "VCC1")
		(14 "In6.Cu" signal "GND2")
		(16 "In7.Cu" signal "IN2")
		(18 "In8.Cu" signal "GND3")
		(2 "B.Cu" signal "BOTTOM")
		(9 "F.Adhes" user "F.Adhesive")
		(11 "B.Adhes" user "B.Adhesive")
		(13 "F.Paste" user "Package Geometry/Pastemask Top")
		(15 "B.Paste" user "Package Geometry/Pastemask Bottom")
		(5 "F.SilkS" user "Ref Des/Silkscreen Top")
		(7 "B.SilkS" user "Ref Des/Silkscreen Bottom")
		(1 "F.Mask" user "Board Geometry/Soldermask Top")
		(3 "B.Mask" user "Board Geometry/Soldermask Bottom")
		(17 "Dwgs.User" user "User.Drawings")
		(19 "Cmts.User" user "User.Comments")
		(21 "Eco1.User" user "User.Eco1")
		(23 "Eco2.User" user "User.Eco2")
		(25 "Edge.Cuts" user "Board Geometry/Outline")
		(27 "Margin" user)
		(31 "F.CrtYd" user "Package Geometry/Place Bound Top")
		(29 "B.CrtYd" user "Package Geometry/Place Bound Bottom")
		(35 "F.Fab" user "Ref Des/Assembly Top")
		(33 "B.Fab" user "Ref Des/Assembly Bottom")
	)
	(footprint ""
		(layer "F.Cu")
		(at 96.8502 -22.225)
		(property "Reference" "ME1"
			(at 0 0 0)
			(layer "F.SilkS")
			(hide yes)
			(effects
				(font
					(size 1.27 1.27)
				)
			)
		)
		(property "Value" ""
			(at 0 0 0)
			(layer "F.Fab")
			(effects
				(font
					(size 1.27 1.27)
				)
			)
		)
		(duplicate_pad_numbers_are_jumpers no)
	)
	(footprint ""
		(layer "F.Cu")
		(at 124.714 -130.175)
		(property "Reference" "PC22"
			(at 0 0 0)
			(layer "F.SilkS")
			(hide yes)
			(effects
				(font
					(size 1.27 1.27)
				)
			)
		)
		(property "Value" ""
			(at 0 0 0)
			(layer "F.Fab")
			(effects
				(font
					(size 1.27 1.27)
				)
			)
		)
		(duplicate_pad_numbers_are_jumpers no)
		(fp_line
			(start -2.2098 -0.9398)
			(end 2.2098 -0.9398)
			(stroke
				(width 0.1524)
				(type default)
			)
			(layer "F.SilkS")
		)
		(fp_line
			(start -2.2098 0.9398)
			(end -2.2098 -0.9398)
			(stroke
				(width 0.1524)
				(type default)
			)
			(layer "F.SilkS")
		)
		(fp_line
			(start 2.2098 -0.9398)
			(end 2.2098 0.9398)
			(stroke
				(width 0.1524)
				(type default)
			)
			(layer "F.SilkS")
		)
		(fp_line
			(start 2.2098 0.9398)
			(end -2.2098 0.9398)
			(stroke
				(width 0.1524)
				(type default)
			)
			(layer "F.SilkS")
		)
		(fp_line
			(start -1.700022 -0.899922)
			(end 1.700022 -0.899922)
			(stroke
				(width 0.1)
				(type default)
			)
			(layer "F.Fab")
		)
		(fp_line
			(start -1.700022 0.899922)
			(end -1.700022 -0.899922)
			(stroke
				(width 0.1)
				(type default)
			)
			(layer "F.Fab")
		)
		(fp_line
			(start 1.700022 -0.899922)
			(end 1.700022 0.899922)
			(stroke
				(width 0.1)
				(type default)
			)
			(layer "F.Fab")
		)
		(fp_line
			(start 1.700022 0.899922)
			(end -1.700022 0.899922)
			(stroke
				(width 0.1)
				(type default)
			)
			(layer "F.Fab")
		)
		(pad "1" smd rect
			(at -1.4732 0 180)
			(size 1.1684 1.5748)
			(layers "F.Cu" "F.Mask" "F.Paste")
			(net "P52V_HS_FILTER")
		)
		(pad "2" smd rect
			(at 1.4732 0 180)
			(size 1.1684 1.5748)
			(layers "F.Cu" "F.Mask" "F.Paste")
			(net "GND")
		)
	)
	(footprint ""
		(layer "F.Cu")
		(at 301.625 -119.6975)
		(property "Reference" "PR6960"
			(at 0 0 0)
			(layer "F.SilkS")
			(hide yes)
			(effects
				(font
					(size 1.27 1.27)
				)
			)
		)
		(property "Value" ""
			(at 0 0 0)
			(layer "F.Fab")
			(effects
				(font
					(size 1.27 1.27)
				)
			)
		)
		(duplicate_pad_numbers_are_jumpers no)
		(fp_line
			(start -1.2954 -0.5842)
			(end 1.2954 -0.5842)
			(stroke
				(width 0.1524)
				(type default)
			)
			(layer "F.SilkS")
		)
		(fp_line
			(start -1.2954 0.5842)
			(end -1.2954 -0.5842)
			(stroke
				(width 0.1524)
				(type default)
			)
			(layer "F.SilkS")
		)
		(fp_line
			(start 1.2954 -0.5842)
			(end 1.2954 0.5842)
			(stroke
				(width 0.1524)
				(type default)
			)
			(layer "F.SilkS")
		)
		(fp_line
			(start 1.2954 0.5842)
			(end -1.2954 0.5842)
			(stroke
				(width 0.1524)
				(type default)
			)
			(layer "F.SilkS")
		)
		(fp_line
			(start -1.1938 -0.406654)
			(end -0.8636 -0.406654)
			(stroke
				(width 0.1)
				(type default)
			)
			(layer "F.Fab")
		)
		(fp_line
			(start -1.1938 0.4064)
			(end -1.1938 -0.406654)
			(stroke
				(width 0.1)
				(type default)
			)
			(layer "F.Fab")
		)
		(fp_line
			(start -0.8636 -0.4572)
			(end 0.8636 -0.4572)
			(stroke
				(width 0.1)
				(type default)
			)
			(layer "F.Fab")
		)
		(fp_line
			(start -0.8636 -0.406654)
			(end -0.8636 -0.4572)
			(stroke
				(width 0.1)
				(type default)
			)
			(layer "F.Fab")
		)
		(fp_line
			(start -0.8636 0.4064)
			(end -1.1938 0.4064)
			(stroke
				(width 0.1)
				(type default)
			)
			(layer "F.Fab")
		)
		(fp_line
			(start -0.8636 0.4318)
			(end -0.8636 0.4064)
			(stroke
				(width 0.1)
				(type default)
			)
			(layer "F.Fab")
		)
		(fp_line
			(start -0.8636 0.4572)
			(end -0.8636 0.4318)
			(stroke
				(width 0.1)
				(type default)
			)
			(layer "F.Fab")
		)
		(fp_line
			(start 0.8636 -0.4572)
			(end 0.8636 -0.406654)
			(stroke
				(width 0.1)
				(type default)
			)
			(layer "F.Fab")
		)
		(fp_line
			(start 0.8636 -0.406654)
			(end 1.1938 -0.406654)
			(stroke
				(width 0.1)
				(type default)
			)
			(layer "F.Fab")
		)
		(fp_line
			(start 0.8636 0.4064)
			(end 0.8636 0.4572)
			(stroke
				(width 0.1)
				(type default)
			)
			(layer "F.Fab")
		)
		(fp_line
			(start 0.8636 0.4572)
			(end -0.8636 0.4572)
			(stroke
				(width 0.1)
				(type default)
			)
			(layer "F.Fab")
		)
		(fp_line
			(start 1.1938 -0.406654)
			(end 1.1938 0.4064)
			(stroke
				(width 0.1)
				(type default)
			)
			(layer "F.Fab")
		)
		(fp_line
			(start 1.1938 0.4064)
			(end 0.8636 0.4064)
			(stroke
				(width 0.1)
				(type default)
			)
			(layer "F.Fab")
		)
		(pad "1" smd rect
			(at -0.7366 0 270)
			(size 0.7112 0.8128)
			(layers "F.Cu" "F.Mask" "F.Paste")
			(net "P52V_HS_1272_S_P")
		)
		(pad "2" smd rect
			(at 0.7366 0 270)
			(size 0.7112 0.8128)
			(layers "F.Cu" "F.Mask" "F.Paste")
			(net "P52V_HS1_SENSE_P_R1")
		)
	)
	(footprint ""
		(layer "F.Cu")
		(at 120.015 -60.96)
		(property "Reference" "PC70"
			(at -1.397 -3.52933 0)
			(unlocked yes)
			(layer "F.SilkS")
			(effects
				(font
					(size 0.7874 0.5842)
					(thickness 0.1524)
				)
				(justify left)
			)
		)
		(property "Value" ""
			(at 0 0 0)
			(layer "F.Fab")
			(effects
				(font
					(size 1.27 1.27)
				)
			)
		)
		(duplicate_pad_numbers_are_jumpers no)
		(fp_line
			(start 5.2578 2.499868)
			(end -5.2578 2.499868)
			(stroke
				(width 0.1524)
				(type default)
			)
			(layer "F.SilkS")
		)
		(fp_circle
			(center 0 2.499868)
			(end 5.2578 2.499868)
			(stroke
				(width 0.1524)
				(type default)
			)
			(fill no)
			(layer "F.SilkS")
		)
		(fp_poly
			(pts
				(arc
					(start 5.2578 2.499868)
					(mid 0 7.757922)
					(end -5.2578 2.499868)
				)
			)
			(stroke
				(width 0)
				(type default)
			)
			(fill yes)
			(layer "F.SilkS")
		)
		(fp_circle
			(center 0 2.499868)
			(end 5.2578 2.499868)
			(stroke
				(width 0.1)
				(type default)
			)
			(fill no)
			(layer "F.Fab")
		)
		(pad "1" thru_hole rect
			(at 0 0 270)
			(size 1.524 1.524)
			(drill 1.016)
			(layers "*.Cu" "*.Mask")
			(remove_unused_layers no)
			(net "P12V_BRICK")
			(clearance 0)
			(padstack
				(mode front_inner_back)
				(layer "Inner"
					(shape circle)
					(size 1.524 1.524)
					(clearance 0)
				)
				(layer "B.Cu"
					(shape rect)
					(size 1.524 1.524)
					(clearance 0)
				)
			)
		)
		(pad "2" thru_hole circle
			(at 0 4.99999 270)
			(size 1.524 1.524)
			(drill 1.016)
			(layers "*.Cu" "*.Mask")
			(remove_unused_layers no)
			(net "GND")
			(clearance 0)
		)
	)
	(footprint ""
		(layer "F.Cu")
		(at 294.9448 -42.164 -90)
		(property "Reference" "PC559"
			(at 0 0 270)
			(layer "F.SilkS")
			(hide yes)
			(effects
				(font
					(size 1.27 1.27)
				)
			)
		)
		(property "Value" ""
			(at 0 0 270)
			(layer "F.Fab")
			(effects
				(font
					(size 1.27 1.27)
				)
			)
		)
		(duplicate_pad_numbers_are_jumpers no)
		(fp_line
			(start -2.2098 0.9398)
			(end -2.2098 -0.9398)
			(stroke
				(width 0.1524)
				(type default)
			)
			(layer "F.SilkS")
		)
		(fp_line
			(start 2.2098 0.9398)
			(end -2.2098 0.9398)
			(stroke
				(width 0.1524)
				(type default)
			)
			(layer "F.SilkS")
		)
		(fp_line
			(start -2.2098 -0.9398)
			(end 2.2098 -0.9398)
			(stroke
				(width 0.1524)
				(type default)
			)
			(layer "F.SilkS")
		)
		(fp_line
			(start 2.2098 -0.9398)
			(end 2.2098 0.9398)
			(stroke
				(width 0.1524)
				(type default)
			)
			(layer "F.SilkS")
		)
		(fp_line
			(start -1.6764 0.9398)
			(end -1.6764 0.889)
			(stroke
				(width 0.1)
				(type default)
			)
			(layer "F.Fab")
		)
		(fp_line
			(start 1.6764 0.9398)
			(end -1.6764 0.9398)
			(stroke
				(width 0.1)
				(type default)
			)
			(layer "F.Fab")
		)
		(fp_line
			(start -1.6764 0.889)
			(end -1.6764 0.8382)
			(stroke
				(width 0.1)
				(type default)
			)
			(layer "F.Fab")
		)
		(fp_line
			(start 1.6764 0.889)
			(end 1.6764 0.9398)
			(stroke
				(width 0.1)
				(type default)
			)
			(layer "F.Fab")
		)
		(fp_line
			(start -2.1082 0.8382)
			(end -2.1082 -0.8382)
			(stroke
				(width 0.1)
				(type default)
			)
			(layer "F.Fab")
		)
		(fp_line
			(start -1.6764 0.8382)
			(end -2.1082 0.8382)
			(stroke
				(width 0.1)
				(type default)
			)
			(layer "F.Fab")
		)
		(fp_line
			(start 1.6764 0.8382)
			(end 1.6764 0.889)
			(stroke
				(width 0.1)
				(type default)
			)
			(layer "F.Fab")
		)
		(fp_line
			(start 2.1082 0.8382)
			(end 1.6764 0.8382)
			(stroke
				(width 0.1)
				(type default)
			)
			(layer "F.Fab")
		)
		(fp_line
			(start -2.1082 -0.8382)
			(end -1.6764 -0.8382)
			(stroke
				(width 0.1)
				(type default)
			)
			(layer "F.Fab")
		)
		(fp_line
			(start -1.6764 -0.8382)
			(end -1.6764 -0.889)
			(stroke
				(width 0.1)
				(type default)
			)
			(layer "F.Fab")
		)
		(fp_line
			(start 1.6764 -0.8382)
			(end 2.1082 -0.8382)
			(stroke
				(width 0.1)
				(type default)
			)
			(layer "F.Fab")
		)
		(fp_line
			(start 2.1082 -0.8382)
			(end 2.1082 0.8382)
			(stroke
				(width 0.1)
				(type default)
			)
			(layer "F.Fab")
		)
		(fp_line
			(start -1.6764 -0.889)
			(end -1.6764 -0.9398)
			(stroke
				(width 0.1)
				(type default)
			)
			(layer "F.Fab")
		)
		(fp_line
			(start 1.6764 -0.889)
			(end 1.6764 -0.8382)
			(stroke
				(width 0.1)
				(type default)
			)
			(layer "F.Fab")
		)
		(fp_line
			(start -1.6764 -0.9398)
			(end 1.6764 -0.9398)
			(stroke
				(width 0.1)
				(type default)
			)
			(layer "F.Fab")
		)
		(fp_line
			(start 1.6764 -0.9398)
			(end 1.6764 -0.889)
			(stroke
				(width 0.1)
				(type default)
			)
			(layer "F.Fab")
		)
		(pad "1" smd rect
			(at -1.4732 0 90)
			(size 1.1684 1.5748)
			(layers "F.Cu" "F.Mask" "F.Paste")
			(net "P52V_HS")
		)
		(pad "2" smd rect
			(at 1.4732 0 90)
			(size 1.1684 1.5748)
			(layers "F.Cu" "F.Mask" "F.Paste")
			(net "P52V_HS1_VCP")
		)
	)
	(footprint ""
		(layer "F.Cu")
		(at 106.426 -51.943)
		(property "Reference" "PC64"
			(at 0 0 0)
			(layer "F.SilkS")
			(hide yes)
			(effects
				(font
					(size 1.27 1.27)
				)
			)
		)
		(property "Value" ""
			(at 0 0 0)
			(layer "F.Fab")
			(effects
				(font
					(size 1.27 1.27)
				)
			)
		)
		(duplicate_pad_numbers_are_jumpers no)
		(fp_line
			(start -1.524 -0.762)
			(end 1.524 -0.762)
			(stroke
				(width 0.1524)
				(type default)
			)
			(layer "F.SilkS")
		)
		(fp_line
			(start -1.524 0.762)
			(end -1.524 -0.762)
			(stroke
				(width 0.1524)
				(type default)
			)
			(layer "F.SilkS")
		)
		(fp_line
			(start 1.524 -0.762)
			(end 1.524 0.762)
			(stroke
				(width 0.1524)
				(type default)
			)
			(layer "F.SilkS")
		)
		(fp_line
			(start 1.524 0.762)
			(end -1.524 0.762)
			(stroke
				(width 0.1524)
				(type default)
			)
			(layer "F.SilkS")
		)
		(fp_line
			(start -1.1049 -0.724916)
			(end -1.1049 0.724916)
			(stroke
				(width 0.1)
				(type default)
			)
			(layer "F.Fab")
		)
		(fp_line
			(start -1.1049 0.724916)
			(end 1.1049 0.724916)
			(stroke
				(width 0.1)
				(type default)
			)
			(layer "F.Fab")
		)
		(fp_line
			(start 1.1049 -0.724916)
			(end -1.1049 -0.724916)
			(stroke
				(width 0.1)
				(type default)
			)
			(layer "F.Fab")
		)
		(fp_line
			(start 1.1049 0.724916)
			(end 1.1049 -0.724916)
			(stroke
				(width 0.1)
				(type default)
			)
			(layer "F.Fab")
		)
		(pad "1" smd rect
			(at -0.889 0 180)
			(size 1.016 1.27)
			(layers "F.Cu" "F.Mask" "F.Paste")
			(net "P12V_BRICK")
		)
		(pad "2" smd rect
			(at 0.889 0 180)
			(size 1.016 1.27)
			(layers "F.Cu" "F.Mask" "F.Paste")
			(net "GND")
		)
	)
	(footprint ""
		(layer "F.Cu")
		(at 179.06746 -51.816)
		(property "Reference" "PC127"
			(at 0 0 0)
			(layer "F.SilkS")
			(hide yes)
			(effects
				(font
					(size 1.27 1.27)
				)
			)
		)
		(property "Value" ""
			(at 0 0 0)
			(layer "F.Fab")
			(effects
				(font
					(size 1.27 1.27)
				)
			)
		)
		(duplicate_pad_numbers_are_jumpers no)
		(fp_line
			(start -1.524 -0.762)
			(end 1.524 -0.762)
			(stroke
				(width 0.1524)
				(type default)
			)
			(layer "F.SilkS")
		)
		(fp_line
			(start -1.524 0.762)
			(end -1.524 -0.762)
			(stroke
				(width 0.1524)
				(type default)
			)
			(layer "F.SilkS")
		)
		(fp_line
			(start 1.524 -0.762)
			(end 1.524 0.762)
			(stroke
				(width 0.1524)
				(type default)
			)
			(layer "F.SilkS")
		)
		(fp_line
			(start 1.524 0.762)
			(end -1.524 0.762)
			(stroke
				(width 0.1524)
				(type default)
			)
			(layer "F.SilkS")
		)
		(fp_line
			(start -1.1049 -0.724916)
			(end -1.1049 0.724916)
			(stroke
				(width 0.1)
				(type default)
			)
			(layer "F.Fab")
		)
		(fp_line
			(start -1.1049 0.724916)
			(end 1.1049 0.724916)
			(stroke
				(width 0.1)
				(type default)
			)
			(layer "F.Fab")
		)
		(fp_line
			(start 1.1049 -0.724916)
			(end -1.1049 -0.724916)
			(stroke
				(width 0.1)
				(type default)
			)
			(layer "F.Fab")
		)
		(fp_line
			(start 1.1049 0.724916)
			(end 1.1049 -0.724916)
			(stroke
				(width 0.1)
				(type default)
			)
			(layer "F.Fab")
		)
		(pad "1" smd rect
			(at -0.889 0 180)
			(size 1.016 1.27)
			(layers "F.Cu" "F.Mask" "F.Paste")
			(net "P12V_BRICK")
		)
		(pad "2" smd rect
			(at 0.889 0 180)
			(size 1.016 1.27)
			(layers "F.Cu" "F.Mask" "F.Paste")
			(net "GND")
		)
	)
	(footprint ""
		(layer "F.Cu")
		(at 299.65396 -114.412268 180)
		(property "Reference" "PR1"
			(at 3.48996 -4.266438 0)
			(unlocked yes)
			(layer "F.SilkS")
			(effects
				(font
					(size 0.7874 0.5842)
					(thickness 0.1524)
				)
				(justify left)
			)
		)
		(property "Value" ""
			(at 0 0 180)
			(layer "F.Fab")
			(effects
				(font
					(size 1.27 1.27)
				)
			)
		)
		(duplicate_pad_numbers_are_jumpers no)
		(fp_line
			(start 3.9878 3.5814)
			(end -3.9878 3.5814)
			(stroke
				(width 0.1524)
				(type default)
			)
			(layer "F.SilkS")
		)
		(fp_line
			(start 3.9878 -3.5814)
			(end 3.9878 3.5814)
			(stroke
				(width 0.1524)
				(type default)
			)
			(layer "F.SilkS")
		)
		(fp_line
			(start -3.9878 3.5814)
			(end -3.9878 -3.5814)
			(stroke
				(width 0.1524)
				(type default)
			)
			(layer "F.SilkS")
		)
		(fp_line
			(start -3.9878 -3.5814)
			(end 3.9878 -3.5814)
			(stroke
				(width 0.1524)
				(type default)
			)
			(layer "F.SilkS")
		)
		(fp_line
			(start 3.5306 3.353054)
			(end -3.5306 3.353054)
			(stroke
				(width 0.1)
				(type default)
			)
			(layer "F.Fab")
		)
		(fp_line
			(start 3.5306 -3.353054)
			(end 3.5306 3.353054)
			(stroke
				(width 0.1)
				(type default)
			)
			(layer "F.Fab")
		)
		(fp_line
			(start -3.5306 3.353054)
			(end -3.5306 -3.353054)
			(stroke
				(width 0.1)
				(type default)
			)
			(layer "F.Fab")
		)
		(fp_line
			(start -3.5306 -3.353054)
			(end 3.5306 -3.353054)
			(stroke
				(width 0.1)
				(type default)
			)
			(layer "F.Fab")
		)
		(pad "1A" smd rect
			(at -2.249932 0)
			(size 3.2004 6.858)
			(layers "F.Cu" "F.Mask" "F.Paste")
			(net "P52V_1")
		)
		(pad "1B" smd rect
			(at -0.776732 0 180)
			(size 0.254 0.508)
			(layers "F.Cu" "F.Mask" "F.Paste")
			(net "P52V_HS1_SENSE_P_R1")
		)
		(pad "2A" smd rect
			(at 2.249932 0)
			(size 3.2004 6.858)
			(layers "F.Cu" "F.Mask" "F.Paste")
			(net "P52V_HS1_DRAIN_1")
		)
		(pad "2B" smd rect
			(at 0.776732 0 180)
			(size 0.254 0.508)
			(layers "F.Cu" "F.Mask" "F.Paste")
			(net "P52V_HS1_SENSE_N_R1")
		)
	)
	(footprint ""
		(layer "F.Cu")
		(at 281.98191 -56.957214 180)
		(property "Reference" "PR6969"
			(at 0 0 180)
			(layer "F.SilkS")
			(hide yes)
			(effects
				(font
					(size 1.27 1.27)
				)
			)
		)
		(property "Value" ""
			(at 0 0 180)
			(layer "F.Fab")
			(effects
				(font
					(size 1.27 1.27)
				)
			)
		)
		(duplicate_pad_numbers_are_jumpers no)
		(fp_line
			(start 0.7874 0.4064)
			(end -0.7874 0.4064)
			(stroke
				(width 0.1524)
				(type default)
			)
			(layer "F.SilkS")
		)
		(fp_line
			(start 0.7874 -0.4064)
			(end 0.7874 0.4064)
			(stroke
				(width 0.1524)
				(type default)
			)
			(layer "F.SilkS")
		)
		(fp_line
			(start -0.7874 0.4064)
			(end -0.7874 -0.4064)
			(stroke
				(width 0.1524)
				(type default)
			)
			(layer "F.SilkS")
		)
		(fp_line
			(start -0.7874 -0.4064)
			(end 0.7874 -0.4064)
			(stroke
				(width 0.1524)
				(type default)
			)
			(layer "F.SilkS")
		)
		(fp_line
			(start 0.67945 0.3048)
			(end 0.120396 0.3048)
			(stroke
				(width 0.1)
				(type default)
			)
			(layer "F.Fab")
		)
		(fp_line
			(start 0.67945 -0.3048)
			(end 0.67945 0.3048)
			(stroke
				(width 0.1)
				(type default)
			)
			(layer "F.Fab")
		)
		(fp_line
			(start 0.12065 -0.2794)
			(end 0.12065 -0.3048)
			(stroke
				(width 0.1)
				(type default)
			)
			(layer "F.Fab")
		)
		(fp_line
			(start 0.12065 -0.3048)
			(end 0.67945 -0.3048)
			(stroke
				(width 0.1)
				(type default)
			)
			(layer "F.Fab")
		)
		(fp_line
			(start 0.120396 0.3048)
			(end 0.120396 0.2794)
			(stroke
				(width 0.1)
				(type default)
			)
			(layer "F.Fab")
		)
		(fp_line
			(start 0.120396 0.2794)
			(end -0.12065 0.2794)
			(stroke
				(width 0.1)
				(type default)
			)
			(layer "F.Fab")
		)
		(fp_line
			(start -0.12065 0.3048)
			(end -0.67945 0.3048)
			(stroke
				(width 0.1)
				(type default)
			)
			(layer "F.Fab")
		)
		(fp_line
			(start -0.12065 0.2794)
			(end -0.12065 0.3048)
			(stroke
				(width 0.1)
				(type default)
			)
			(layer "F.Fab")
		)
		(fp_line
			(start -0.12065 -0.2794)
			(end 0.12065 -0.2794)
			(stroke
				(width 0.1)
				(type default)
			)
			(layer "F.Fab")
		)
		(fp_line
			(start -0.12065 -0.305054)
			(end -0.12065 -0.2794)
			(stroke
				(width 0.1)
				(type default)
			)
			(layer "F.Fab")
		)
		(fp_line
			(start -0.67945 0.3048)
			(end -0.67945 -0.305054)
			(stroke
				(width 0.1)
				(type default)
			)
			(layer "F.Fab")
		)
		(fp_line
			(start -0.67945 -0.305054)
			(end -0.12065 -0.305054)
			(stroke
				(width 0.1)
				(type default)
			)
			(layer "F.Fab")
		)
		(pad "1" smd rect
			(at -0.40005 0)
			(size 0.4572 0.508)
			(layers "F.Cu" "F.Mask" "F.Paste")
			(net "P52V_HS1_TEMPN_R")
		)
		(pad "2" smd rect
			(at 0.40005 0)
			(size 0.4572 0.508)
			(layers "F.Cu" "F.Mask" "F.Paste")
			(net "GND_FIELD_SIGNAL")
		)
	)
)
